# T6G (Grand Teton) — schematic netlist excerpt (pin names and nets, part order shuffled) for the footprints in the layout excerpt that follows; sources: Cadence DE-HDL packaged netlist, KiCad conversion of 04192023_DAF0TMB3IC0_F0TG_MB_C_brd_V02_OCP.brd

PC2226  Q_CAP  0.068UF 16V 10% X7R  pkg 0402  page 264 : A = HSC_SS ; B = AGND_HSC
R475  Q_RES  33 5% CHIP  pkg 0402LF  page 29 : A = SPI_CPU0_TPM_CS_N ; B = SPI_CPU0_R_TPM_CS_N

(kicad_pcb
	(version 20260206)
	(generator "pcbnew")
	(generator_version "10.0")
	(general
		(thickness 1.6)
		(legacy_teardrops no)
	)
	(paper "A4")
	(title_block
		(title "04192023_DAF0TMB3IC0_F0TG_MB_C_brd_V02_OCP.brd")
		(comment 1 "Grand Teton / footprints 2959-2960 of 8354")
	)
	(layers
		(0 "F.Cu" signal "TOP")
		(4 "In1.Cu" signal "GND")
		(6 "In2.Cu" signal "IN1")
		(8 "In3.Cu" signal "GND1")
		(10 "In4.Cu" signal "IN2")
		(12 "In5.Cu" signal "GND2")
		(14 "In6.Cu" signal "IN3")
		(16 "In7.Cu" signal "GND3")
		(18 "In8.Cu" signal "VCC")
		(20 "In9.Cu" signal "VCC1")
		(22 "In10.Cu" signal "GND4")
		(24 "In11.Cu" signal "IN4")
		(26 "In12.Cu" signal "GND5")
		(28 "In13.Cu" signal "IN5")
		(30 "In14.Cu" signal "GND6")
		(32 "In15.Cu" signal "IN6")
		(34 "In16.Cu" signal "GND7")
		(2 "B.Cu" signal "BOTTOM")
		(9 "F.Adhes" user "F.Adhesive")
		(11 "B.Adhes" user "B.Adhesive")
		(13 "F.Paste" user "Package Geometry/Pastemask Top")
		(15 "B.Paste" user "Package Geometry/Pastemask Bottom")
		(5 "F.SilkS" user "Ref Des/Silkscreen Top")
		(7 "B.SilkS" user "Ref Des/Silkscreen Bottom")
		(1 "F.Mask" user "Board Geometry/Soldermask Top")
		(3 "B.Mask" user "Board Geometry/Soldermask Bottom")
		(17 "Dwgs.User" user "User.Drawings")
		(19 "Cmts.User" user "User.Comments")
		(21 "Eco1.User" user "User.Eco1")
		(23 "Eco2.User" user "User.Eco2")
		(25 "Edge.Cuts" user "Board Geometry/Outline")
		(27 "Margin" user)
		(31 "F.CrtYd" user "Package Geometry/Place Bound Top")
		(29 "B.CrtYd" user "Package Geometry/Place Bound Bottom")
		(35 "F.Fab" user "Ref Des/Assembly Top")
		(33 "B.Fab" user "Ref Des/Assembly Bottom")
	)
	(footprint ""
		(layer "F.Cu")
		(at 215.4301 -405.036782 180)
		(property "Reference" "PC2226"
			(at 0 0 180)
			(layer "F.SilkS")
			(hide yes)
			(effects
				(font
					(size 1.27 1.27)
				)
			)
		)
		(property "Value" ""
			(at 0 0 180)
			(layer "F.Fab")
			(effects
				(font
					(size 1.27 1.27)
				)
			)
		)
		(duplicate_pad_numbers_are_jumpers no)
		(fp_line
			(start 0.7874 0.4064)
			(end -0.7874 0.4064)
			(stroke
				(width 0.1524)
				(type default)
			)
			(layer "F.SilkS")
		)
		(fp_line
			(start 0.7874 -0.4064)
			(end 0.7874 0.4064)
			(stroke
				(width 0.1524)
				(type default)
			)
			(layer "F.SilkS")
		)
		(fp_line
			(start -0.7874 0.4064)
			(end -0.7874 -0.4064)
			(stroke
				(width 0.1524)
				(type default)
			)
			(layer "F.SilkS")
		)
		(fp_line
			(start -0.7874 -0.4064)
			(end 0.7874 -0.4064)
			(stroke
				(width 0.1524)
				(type default)
			)
			(layer "F.SilkS")
		)
		(fp_line
			(start 0.67945 0.3048)
			(end 0.120396 0.3048)
			(stroke
				(width 0.1)
				(type default)
			)
			(layer "F.Fab")
		)
		(fp_line
			(start 0.67945 -0.3048)
			(end 0.67945 0.3048)
			(stroke
				(width 0.1)
				(type default)
			)
			(layer "F.Fab")
		)
		(fp_line
			(start 0.12065 -0.2794)
			(end 0.12065 -0.3048)
			(stroke
				(width 0.1)
				(type default)
			)
			(layer "F.Fab")
		)
		(fp_line
			(start 0.12065 -0.3048)
			(end 0.67945 -0.3048)
			(stroke
				(width 0.1)
				(type default)
			)
			(layer "F.Fab")
		)
		(fp_line
			(start 0.120396 0.3048)
			(end 0.120396 0.2794)
			(stroke
				(width 0.1)
				(type default)
			)
			(layer "F.Fab")
		)
		(fp_line
			(start 0.120396 0.2794)
			(end -0.12065 0.2794)
			(stroke
				(width 0.1)
				(type default)
			)
			(layer "F.Fab")
		)
		(fp_line
			(start -0.12065 0.3048)
			(end -0.67945 0.3048)
			(stroke
				(width 0.1)
				(type default)
			)
			(layer "F.Fab")
		)
		(fp_line
			(start -0.12065 0.2794)
			(end -0.12065 0.3048)
			(stroke
				(width 0.1)
				(type default)
			)
			(layer "F.Fab")
		)
		(fp_line
			(start -0.12065 -0.2794)
			(end 0.12065 -0.2794)
			(stroke
				(width 0.1)
				(type default)
			)
			(layer "F.Fab")
		)
		(fp_line
			(start -0.12065 -0.305054)
			(end -0.12065 -0.2794)
			(stroke
				(width 0.1)
				(type default)
			)
			(layer "F.Fab")
		)
		(fp_line
			(start -0.67945 0.3048)
			(end -0.67945 -0.305054)
			(stroke
				(width 0.1)
				(type default)
			)
			(layer "F.Fab")
		)
		(fp_line
			(start -0.67945 -0.305054)
			(end -0.12065 -0.305054)
			(stroke
				(width 0.1)
				(type default)
			)
			(layer "F.Fab")
		)
		(pad "1" smd circle
			(at -0.40005 0 180)
			(size 0 0)
			(layers "F.Cu" "F.Mask" "F.Paste")
			(net "HSC_SS")
		)
		(pad "2" smd circle
			(at 0.40005 0 180)
			(size 0 0)
			(layers "F.Cu" "F.Mask" "F.Paste")
			(net "AGND_HSC")
		)
	)
	(footprint ""
		(layer "F.Cu")
		(at 400.48307 -323.965316 180)
		(property "Reference" "R475"
			(at 0 0 180)
			(layer "F.SilkS")
			(hide yes)
			(effects
				(font
					(size 1.27 1.27)
				)
			)
		)
		(property "Value" ""
			(at 0 0 180)
			(layer "F.Fab")
			(effects
				(font
					(size 1.27 1.27)
				)
			)
		)
		(duplicate_pad_numbers_are_jumpers no)
		(fp_line
			(start 0.7874 0.4064)
			(end -0.7874 0.4064)
			(stroke
				(width 0.1524)
				(type default)
			)
			(layer "F.SilkS")
		)
		(fp_line
			(start 0.7874 -0.4064)
			(end 0.7874 0.4064)
			(stroke
				(width 0.1524)
				(type default)
			)
			(layer "F.SilkS")
		)
		(fp_line
			(start -0.7874 0.4064)
			(end -0.7874 -0.4064)
			(stroke
				(width 0.1524)
				(type default)
			)
			(layer "F.SilkS")
		)
		(fp_line
			(start -0.7874 -0.4064)
			(end 0.7874 -0.4064)
			(stroke
				(width 0.1524)
				(type default)
			)
			(layer "F.SilkS")
		)
		(fp_line
			(start 0.67945 0.3048)
			(end 0.120396 0.3048)
			(stroke
				(width 0.1)
				(type default)
			)
			(layer "F.Fab")
		)
		(fp_line
			(start 0.67945 -0.3048)
			(end 0.67945 0.3048)
			(stroke
				(width 0.1)
				(type default)
			)
			(layer "F.Fab")
		)
		(fp_line
			(start 0.12065 -0.2794)
			(end 0.12065 -0.3048)
			(stroke
				(width 0.1)
				(type default)
			)
			(layer "F.Fab")
		)
		(fp_line
			(start 0.12065 -0.3048)
			(end 0.67945 -0.3048)
			(stroke
				(width 0.1)
				(type default)
			)
			(layer "F.Fab")
		)
		(fp_line
			(start 0.120396 0.3048)
			(end 0.120396 0.2794)
			(stroke
				(width 0.1)
				(type default)
			)
			(layer "F.Fab")
		)
		(fp_line
			(start 0.120396 0.2794)
			(end -0.12065 0.2794)
			(stroke
				(width 0.1)
				(type default)
			)
			(layer "F.Fab")
		)
		(fp_line
			(start -0.12065 0.3048)
			(end -0.67945 0.3048)
			(stroke
				(width 0.1)
				(type default)
			)
			(layer "F.Fab")
		)
		(fp_line
			(start -0.12065 0.2794)
			(end -0.12065 0.3048)
			(stroke
				(width 0.1)
				(type default)
			)
			(layer "F.Fab")
		)
		(fp_line
			(start -0.12065 -0.2794)
			(end 0.12065 -0.2794)
			(stroke
				(width 0.1)
				(type default)
			)
			(layer "F.Fab")
		)
		(fp_line
			(start -0.12065 -0.305054)
			(end -0.12065 -0.2794)
			(stroke
				(width 0.1)
				(type default)
			)
			(layer "F.Fab")
		)
		(fp_line
			(start -0.67945 0.3048)
			(end -0.67945 -0.305054)
			(stroke
				(width 0.1)
				(type default)
			)
			(layer "F.Fab")
		)
		(fp_line
			(start -0.67945 -0.305054)
			(end -0.12065 -0.305054)
			(stroke
				(width 0.1)
				(type default)
			)
			(layer "F.Fab")
		)
		(pad "1" smd circle
			(at -0.40005 0 180)
			(size 0 0)
			(layers "F.Cu" "F.Mask" "F.Paste")
			(net "SPI_CPU0_TPM_CS_N")
		)
		(pad "2" smd circle
			(at 0.40005 0 180)
			(size 0 0)
			(layers "F.Cu" "F.Mask" "F.Paste")
			(net "SPI_CPU0_R_TPM_CS_N")
		)
	)
)
